(kicad_pcb
	(version 20260206)
	(generator "pcbnew")
	(generator_version "10.0")
	(general
		(thickness 1.6)
		(legacy_teardrops no)
	)
	(paper "A4")
	(title_block
		(title "netronome-mezz — pcbd0082-001_rev01_jul9_a.brd")
		(comment 1 "Open CloudServer (Microsoft) / footprints 620-629 of 714")
	)
	(layers
		(0 "F.Cu" signal "TOP")
		(4 "In1.Cu" signal "02_GND")
		(6 "In2.Cu" signal "03_SIG")
		(8 "In3.Cu" signal "04_SIG")
		(10 "In4.Cu" signal "05_GND")
		(12 "In5.Cu" signal "06_PWR1")
		(14 "In6.Cu" signal "07_SIG")
		(16 "In7.Cu" signal "08_SIG")
		(18 "In8.Cu" signal "09_GND")
		(2 "B.Cu" signal "BOTTOM")
		(9 "F.Adhes" user "F.Adhesive")
		(11 "B.Adhes" user "B.Adhesive")
		(13 "F.Paste" user "Package Geometry/Pastemask Top")
		(15 "B.Paste" user "Package Geometry/Pastemask Bottom")
		(5 "F.SilkS" user "Ref Des/Silkscreen Top")
		(7 "B.SilkS" user "Ref Des/Silkscreen Bottom")
		(1 "F.Mask" user "Board Geometry/Soldermask Top")
		(3 "B.Mask" user "Board Geometry/Soldermask Bottom")
		(17 "Dwgs.User" user "User.Drawings")
		(19 "Cmts.User" user "User.Comments")
		(21 "Eco1.User" user "User.Eco1")
		(23 "Eco2.User" user "User.Eco2")
		(25 "Edge.Cuts" user "Board Geometry/Outline")
		(27 "Margin" user)
		(31 "F.CrtYd" user "Package Geometry/Place Bound Top")
		(29 "B.CrtYd" user "Package Geometry/Place Bound Bottom")
		(35 "F.Fab" user "Ref Des/Assembly Top")
		(33 "B.Fab" user "Ref Des/Assembly Bottom")
		(45 "User.4" user "COMPVAL_TYPE_BOTTOM")
	)
	(footprint ""
		(layer "B.Cu")
		(at 50.477039 0.762 180)
		(property "Reference" "C150"
			(at 0.145212 0.8763 270)
			(unlocked yes)
			(layer "B.SilkS")
			(effects
				(font
					(size 0.7874 0.5842)
					(thickness 0.127)
				)
				(justify left mirror)
			)
		)
		(property "Value" "0.22UF"
			(at 0.091846 0.2921 90)
			(unlocked yes)
			(layer "B.Fab")
			(hide yes)
			(effects
				(font
					(size 0.7874 0.5842)
					(thickness 0.2032)
				)
				(justify left mirror)
			)
		)
		(property "Device Type" "CAPC0062"
			(at 0.091846 0.2921 90)
			(unlocked yes)
			(layer "B.Fab")
			(hide yes)
			(effects
				(font
					(size 0.7874 0.5842)
					(thickness 0.2032)
				)
				(justify left mirror)
			)
		)
		(duplicate_pad_numbers_are_jumpers no)
		(fp_poly
			(pts
				(xy -0.635 1.0668) (xy -0.635 -1.0668) (xy 0.635 -1.0668) (xy 0.635 1.0668)
			)
			(stroke
				(width 0)
				(type default)
			)
			(fill no)
			(layer "B.CrtYd")
		)
		(fp_line
			(start 0.254 0.508)
			(end 0.254 -0.508)
			(stroke
				(width 0.0254)
				(type default)
			)
			(layer "B.Fab")
		)
		(fp_line
			(start 0.254 -0.508)
			(end -0.254 -0.508)
			(stroke
				(width 0.0254)
				(type default)
			)
			(layer "B.Fab")
		)
		(fp_line
			(start -0.254 0.508)
			(end 0.254 0.508)
			(stroke
				(width 0.0254)
				(type default)
			)
			(layer "B.Fab")
		)
		(fp_line
			(start -0.254 -0.508)
			(end -0.254 0.508)
			(stroke
				(width 0.0254)
				(type default)
			)
			(layer "B.Fab")
		)
		(pad "1" smd rect
			(at 0 -0.4191)
			(size 0.508 0.5334)
			(layers "B.Cu" "B.Mask" "B.Paste")
			(net "_NFP_PCIE0_PER6_N")
		)
		(pad "2" smd rect
			(at 0 0.4191)
			(size 0.508 0.5334)
			(layers "B.Cu" "B.Mask" "B.Paste")
			(net "NFP_PCIE0_PER6_N")
		)
		(zone
			(layer "B.Cu")
			(hatch none 0.5)
			(connect_pads
				(clearance 0)
			)
			(min_thickness 0.25)
			(keepout
				(tracks not_allowed)
				(vias allowed)
				(pads allowed)
				(copperpour not_allowed)
				(footprints allowed)
			)
			(placement
				(enabled no)
				(sheetname "")
			)
			(fill
				(thermal_gap 0.5)
				(thermal_bridge_width 0.5)
				(island_removal_mode 0)
			)
			(polygon
				(pts
					(xy 50.502439 0.7874) (xy 50.502439 0.7366) (xy 50.451639 0.7366) (xy 50.451639 0.7874)
				)
			)
		)
	)
	(footprint ""
		(layer "B.Cu")
		(at 28.702 18.923 180)
		(property "Reference" "R54"
			(at 0 0 0)
			(layer "B.SilkS")
			(hide yes)
			(effects
				(font
					(size 1.27 1.27)
				)
				(justify mirror)
			)
		)
		(property "Value" "4.75K"
			(at 0.148158 1.3462 90)
			(unlocked yes)
			(layer "B.Fab")
			(hide yes)
			(effects
				(font
					(size 1.27 0.9652)
					(thickness 0.000001)
				)
				(justify left mirror)
			)
		)
		(property "Device Type" "REST4024"
			(at 0.148158 1.3462 90)
			(unlocked yes)
			(layer "B.Fab")
			(hide yes)
			(effects
				(font
					(size 1.27 0.9652)
					(thickness 0.000001)
				)
				(justify left mirror)
			)
		)
		(duplicate_pad_numbers_are_jumpers no)
		(fp_poly
			(pts
				(xy -0.635 1.0668) (xy -0.635 -1.0668) (xy 0.635 -1.0668) (xy 0.635 1.0668)
			)
			(stroke
				(width 0)
				(type default)
			)
			(fill no)
			(layer "B.CrtYd")
		)
		(fp_line
			(start 0.254 0.508)
			(end 0.254 -0.508)
			(stroke
				(width 0.0254)
				(type default)
			)
			(layer "B.Fab")
		)
		(fp_line
			(start 0.254 -0.508)
			(end -0.254 -0.508)
			(stroke
				(width 0.0254)
				(type default)
			)
			(layer "B.Fab")
		)
		(fp_line
			(start -0.254 0.508)
			(end 0.254 0.508)
			(stroke
				(width 0.0254)
				(type default)
			)
			(layer "B.Fab")
		)
		(fp_line
			(start -0.254 -0.508)
			(end -0.254 0.508)
			(stroke
				(width 0.0254)
				(type default)
			)
			(layer "B.Fab")
		)
		(pad "1" smd rect
			(at 0 -0.4191)
			(size 0.508 0.5334)
			(layers "B.Cu" "B.Mask" "B.Paste")
			(net "CPLD_VERSION_2")
		)
		(pad "2" smd rect
			(at 0 0.4191)
			(size 0.508 0.5334)
			(layers "B.Cu" "B.Mask" "B.Paste")
			(net "GND")
		)
		(zone
			(layer "B.Cu")
			(hatch none 0.5)
			(connect_pads
				(clearance 0)
			)
			(min_thickness 0.25)
			(keepout
				(tracks not_allowed)
				(vias allowed)
				(pads allowed)
				(copperpour not_allowed)
				(footprints allowed)
			)
			(placement
				(enabled no)
				(sheetname "")
			)
			(fill
				(thermal_gap 0.5)
				(thermal_bridge_width 0.5)
				(island_removal_mode 0)
			)
			(polygon
				(pts
					(xy 28.7274 18.9484) (xy 28.7274 18.8976) (xy 28.6766 18.8976) (xy 28.6766 18.9484)
				)
			)
		)
	)
	(footprint ""
		(layer "B.Cu")
		(at 2.032 9.8552 180)
		(property "Reference" "R378"
			(at 0 0 0)
			(layer "B.SilkS")
			(hide yes)
			(effects
				(font
					(size 1.27 1.27)
				)
				(justify mirror)
			)
		)
		(property "Value" "4.75K"
			(at 0.148158 1.3462 90)
			(unlocked yes)
			(layer "B.Fab")
			(hide yes)
			(effects
				(font
					(size 1.27 0.9652)
					(thickness 0.000001)
				)
				(justify left mirror)
			)
		)
		(property "Device Type" "REST4024"
			(at 0.148158 1.3462 90)
			(unlocked yes)
			(layer "B.Fab")
			(hide yes)
			(effects
				(font
					(size 1.27 0.9652)
					(thickness 0.000001)
				)
				(justify left mirror)
			)
		)
		(duplicate_pad_numbers_are_jumpers no)
		(fp_poly
			(pts
				(xy -0.635 1.0668) (xy -0.635 -1.0668) (xy 0.635 -1.0668) (xy 0.635 1.0668)
			)
			(stroke
				(width 0)
				(type default)
			)
			(fill no)
			(layer "B.CrtYd")
		)
		(fp_line
			(start 0.254 0.508)
			(end 0.254 -0.508)
			(stroke
				(width 0.0254)
				(type default)
			)
			(layer "B.Fab")
		)
		(fp_line
			(start 0.254 -0.508)
			(end -0.254 -0.508)
			(stroke
				(width 0.0254)
				(type default)
			)
			(layer "B.Fab")
		)
		(fp_line
			(start -0.254 0.508)
			(end 0.254 0.508)
			(stroke
				(width 0.0254)
				(type default)
			)
			(layer "B.Fab")
		)
		(fp_line
			(start -0.254 -0.508)
			(end -0.254 0.508)
			(stroke
				(width 0.0254)
				(type default)
			)
			(layer "B.Fab")
		)
		(pad "1" smd rect
			(at 0 -0.4191)
			(size 0.508 0.5334)
			(layers "B.Cu" "B.Mask" "B.Paste")
			(net "NWK1_I2C_SDA")
		)
		(pad "2" smd rect
			(at 0 0.4191)
			(size 0.508 0.5334)
			(layers "B.Cu" "B.Mask" "B.Paste")
			(net "EXT_3.3V")
		)
		(zone
			(layer "B.Cu")
			(hatch none 0.5)
			(connect_pads
				(clearance 0)
			)
			(min_thickness 0.25)
			(keepout
				(tracks not_allowed)
				(vias allowed)
				(pads allowed)
				(copperpour not_allowed)
				(footprints allowed)
			)
			(placement
				(enabled no)
				(sheetname "")
			)
			(fill
				(thermal_gap 0.5)
				(thermal_bridge_width 0.5)
				(island_removal_mode 0)
			)
			(polygon
				(pts
					(xy 2.0574 9.8806) (xy 2.0574 9.8298) (xy 2.0066 9.8298) (xy 2.0066 9.8806)
				)
			)
		)
	)
	(footprint ""
		(layer "B.Cu")
		(at 5.334 14.5796)
		(property "Reference" "C283"
			(at 0.86233 3.2004 270)
			(unlocked yes)
			(layer "B.SilkS")
			(effects
				(font
					(size 0.7874 0.5842)
					(thickness 0.127)
				)
				(justify left mirror)
			)
		)
		(property "Value" "4.7UF"
			(at 0.091846 0.2921 270)
			(unlocked yes)
			(layer "B.Fab")
			(hide yes)
			(effects
				(font
					(size 0.7874 0.5842)
					(thickness 0.2032)
				)
				(justify left mirror)
			)
		)
		(property "Device Type" "CAPC0065"
			(at 0.091846 0.2921 270)
			(unlocked yes)
			(layer "B.Fab")
			(hide yes)
			(effects
				(font
					(size 0.7874 0.5842)
					(thickness 0.2032)
				)
				(justify left mirror)
			)
		)
		(duplicate_pad_numbers_are_jumpers no)
		(fp_poly
			(pts
				(xy -0.635 1.0668) (xy -0.635 -1.0668) (xy 0.635 -1.0668) (xy 0.635 1.0668)
			)
			(stroke
				(width 0)
				(type default)
			)
			(fill no)
			(layer "B.CrtYd")
		)
		(fp_line
			(start -0.254 -0.508)
			(end -0.254 0.508)
			(stroke
				(width 0.0254)
				(type default)
			)
			(layer "B.Fab")
		)
		(fp_line
			(start -0.254 0.508)
			(end 0.254 0.508)
			(stroke
				(width 0.0254)
				(type default)
			)
			(layer "B.Fab")
		)
		(fp_line
			(start 0.254 -0.508)
			(end -0.254 -0.508)
			(stroke
				(width 0.0254)
				(type default)
			)
			(layer "B.Fab")
		)
		(fp_line
			(start 0.254 0.508)
			(end 0.254 -0.508)
			(stroke
				(width 0.0254)
				(type default)
			)
			(layer "B.Fab")
		)
		(pad "1" smd rect
			(at 0 -0.4191 180)
			(size 0.508 0.5334)
			(layers "B.Cu" "B.Mask" "B.Paste")
			(net "13N4351")
		)
		(pad "2" smd rect
			(at 0 0.4191 180)
			(size 0.508 0.5334)
			(layers "B.Cu" "B.Mask" "B.Paste")
			(net "GND")
		)
		(zone
			(layer "B.Cu")
			(hatch none 0.5)
			(connect_pads
				(clearance 0)
			)
			(min_thickness 0.25)
			(keepout
				(tracks not_allowed)
				(vias allowed)
				(pads allowed)
				(copperpour not_allowed)
				(footprints allowed)
			)
			(placement
				(enabled no)
				(sheetname "")
			)
			(fill
				(thermal_gap 0.5)
				(thermal_bridge_width 0.5)
				(island_removal_mode 0)
			)
			(polygon
				(pts
					(xy 5.3086 14.5542) (xy 5.3086 14.605) (xy 5.3594 14.605) (xy 5.3594 14.5542)
				)
			)
		)
	)
	(footprint ""
		(layer "B.Cu")
		(at 40.237029 11.542014)
		(property "Reference" "R41"
			(at 0 0 0)
			(layer "B.SilkS")
			(hide yes)
			(effects
				(font
					(size 1.27 1.27)
				)
				(justify mirror)
			)
		)
		(property "Value" ""
			(at 0 0 0)
			(layer "B.Fab")
			(effects
				(font
					(size 1.27 1.27)
				)
				(justify mirror)
			)
		)
		(duplicate_pad_numbers_are_jumpers no)
		(fp_circle
			(center 0 0)
			(end 0.104648 0)
			(stroke
				(width 0.1016)
				(type default)
			)
			(fill no)
			(layer "B.SilkS")
		)
		(fp_poly
			(pts
				(xy 0.381 -0.889) (xy 0.381 0.889) (xy -0.381 0.889) (xy -0.381 -0.889)
			)
			(stroke
				(width 0)
				(type default)
			)
			(fill no)
			(layer "B.CrtYd")
		)
		(fp_line
			(start -0.508 -1.016)
			(end -0.508 1.016)
			(stroke
				(width 0.0254)
				(type default)
			)
			(layer "B.Fab")
		)
		(fp_line
			(start -0.508 1.016)
			(end 0.508 1.016)
			(stroke
				(width 0.0254)
				(type default)
			)
			(layer "B.Fab")
		)
		(fp_line
			(start 0.254 -1.016)
			(end -0.508 -1.016)
			(stroke
				(width 0.0254)
				(type default)
			)
			(layer "B.Fab")
		)
		(fp_line
			(start 0.508 -1.016)
			(end 0.254 -1.016)
			(stroke
				(width 0.0254)
				(type default)
			)
			(layer "B.Fab")
		)
		(fp_line
			(start 0.508 1.016)
			(end 0.508 -1.016)
			(stroke
				(width 0.0254)
				(type default)
			)
			(layer "B.Fab")
		)
		(pad "1" smd custom
			(at 0 -0.500126 180)
			(size 0.127 0.127)
			(layers "B.Cu" "B.Mask" "B.Paste")
			(net "VDD_3.3V")
			(options
				(clearance outline)
				(anchor circle)
			)
			(primitives
				(gr_poly
					(pts
						(xy -0.1778 0.254) (xy 0.1778 0.254) (xy 0.254 0.1778) (xy 0.254 -0.1778) (xy 0.1778 -0.254) (xy -0.1778 -0.254)
						(xy -0.254 -0.1778) (xy -0.254 0.1778)
					)
					(width 0)
					(fill yes)
				)
			)
		)
		(pad "2" smd custom
			(at 0 0.500126 180)
			(size 0.127 0.127)
			(layers "B.Cu" "B.Mask" "B.Paste")
			(net "PGRM_JTAG_TRST_L")
			(options
				(clearance outline)
				(anchor circle)
			)
			(primitives
				(gr_poly
					(pts
						(xy -0.1778 0.254) (xy 0.1778 0.254) (xy 0.254 0.1778) (xy 0.254 -0.1778) (xy 0.1778 -0.254) (xy -0.1778 -0.254)
						(xy -0.254 -0.1778) (xy -0.254 0.1778)
					)
					(width 0)
					(fill yes)
				)
			)
		)
	)
	(footprint ""
		(layer "B.Cu")
		(at 2.032 8.128)
		(property "Reference" "TP30"
			(at -1.524 -0.48133 0)
			(unlocked yes)
			(layer "B.SilkS")
			(effects
				(font
					(size 0.7874 0.5842)
					(thickness 0.127)
				)
				(justify left mirror)
			)
		)
		(property "Value" "*"
			(at 0.4826 -0.14732 0)
			(unlocked yes)
			(layer "B.Fab")
			(hide yes)
			(effects
				(font
					(size 1.27 0.9652)
					(thickness 0.000001)
				)
				(justify left mirror)
			)
		)
		(property "Device Type" "TP_SMALL"
			(at 0.4826 -0.14732 0)
			(unlocked yes)
			(layer "B.Fab")
			(hide yes)
			(effects
				(font
					(size 1.27 0.9652)
					(thickness 0.000001)
				)
				(justify left mirror)
			)
		)
		(duplicate_pad_numbers_are_jumpers no)
		(fp_line
			(start -0.8636 -0.8636)
			(end 0.8636 -0.8636)
			(stroke
				(width 0.1524)
				(type default)
			)
			(layer "B.SilkS")
		)
		(fp_line
			(start -0.8636 0.8636)
			(end -0.8636 -0.8636)
			(stroke
				(width 0.1524)
				(type default)
			)
			(layer "B.SilkS")
		)
		(fp_line
			(start 0.8636 -0.8636)
			(end 0.8636 0.8636)
			(stroke
				(width 0.1524)
				(type default)
			)
			(layer "B.SilkS")
		)
		(fp_line
			(start 0.8636 0.8636)
			(end -0.8636 0.8636)
			(stroke
				(width 0.1524)
				(type default)
			)
			(layer "B.SilkS")
		)
		(fp_poly
			(pts
				(xy 0.635 -0.635) (xy 0.635 0.635) (xy -0.635 0.635) (xy -0.635 -0.635)
			)
			(stroke
				(width 0)
				(type default)
			)
			(fill no)
			(layer "B.CrtYd")
		)
		(pad "1" smd rect
			(at 0 0 180)
			(size 1.27 1.27)
			(layers "B.Cu" "B.Mask" "B.Paste")
			(net "PGRM_JTAG_TMS")
		)
	)
	(footprint ""
		(layer "B.Cu")
		(at 45.737018 11.042015 -90)
		(property "Reference" "R286"
			(at 0 0 90)
			(layer "B.SilkS")
			(hide yes)
			(effects
				(font
					(size 1.27 1.27)
				)
				(justify mirror)
			)
		)
		(property "Value" ""
			(at 0 0 90)
			(layer "B.Fab")
			(effects
				(font
					(size 1.27 1.27)
				)
				(justify mirror)
			)
		)
		(duplicate_pad_numbers_are_jumpers no)
		(fp_circle
			(center 0 0)
			(end 0 -0.104648)
			(stroke
				(width 0.1016)
				(type default)
			)
			(fill no)
			(layer "B.SilkS")
		)
		(fp_poly
			(pts
				(xy 0.381 -0.889) (xy 0.381 0.889) (xy -0.381 0.889) (xy -0.381 -0.889)
			)
			(stroke
				(width 0)
				(type default)
			)
			(fill no)
			(layer "B.CrtYd")
		)
		(fp_line
			(start -0.508 1.016)
			(end 0.508 1.016)
			(stroke
				(width 0.0254)
				(type default)
			)
			(layer "B.Fab")
		)
		(fp_line
			(start 0.508 1.016)
			(end 0.508 -1.016)
			(stroke
				(width 0.0254)
				(type default)
			)
			(layer "B.Fab")
		)
		(fp_line
			(start -0.508 -1.016)
			(end -0.508 1.016)
			(stroke
				(width 0.0254)
				(type default)
			)
			(layer "B.Fab")
		)
		(fp_line
			(start 0.254 -1.016)
			(end -0.508 -1.016)
			(stroke
				(width 0.0254)
				(type default)
			)
			(layer "B.Fab")
		)
		(fp_line
			(start 0.508 -1.016)
			(end 0.254 -1.016)
			(stroke
				(width 0.0254)
				(type default)
			)
			(layer "B.Fab")
		)
		(pad "1" smd custom
			(at 0 -0.500126 90)
			(size 0.127 0.127)
			(layers "B.Cu" "B.Mask" "B.Paste")
			(net "NFP_VDD_CORE_SENSE_VDD")
			(options
				(clearance outline)
				(anchor circle)
			)
			(primitives
				(gr_poly
					(pts
						(xy -0.1778 0.254) (xy 0.1778 0.254) (xy 0.254 0.1778) (xy 0.254 -0.1778) (xy 0.1778 -0.254) (xy -0.1778 -0.254)
						(xy -0.254 -0.1778) (xy -0.254 0.1778)
					)
					(width 0)
					(fill yes)
				)
			)
		)
		(pad "2" smd custom
			(at 0 0.500126 90)
			(size 0.127 0.127)
			(layers "B.Cu" "B.Mask" "B.Paste")
			(net "VDD_CORE")
			(options
				(clearance outline)
				(anchor circle)
			)
			(primitives
				(gr_poly
					(pts
						(xy -0.1778 0.254) (xy 0.1778 0.254) (xy 0.254 0.1778) (xy 0.254 -0.1778) (xy 0.1778 -0.254) (xy -0.1778 -0.254)
						(xy -0.254 -0.1778) (xy -0.254 0.1778)
					)
					(width 0)
					(fill yes)
				)
			)
		)
	)
	(footprint ""
		(layer "B.Cu")
		(at 72.251011 18.255996)
		(property "Reference" "V_A-DQ28"
			(at 0 0 0)
			(layer "B.SilkS")
			(hide yes)
			(effects
				(font
					(size 1.27 1.27)
				)
				(justify mirror)
			)
		)
		(property "Value" ""
			(at 0 0 0)
			(layer "B.Fab")
			(effects
				(font
					(size 1.27 1.27)
				)
				(justify mirror)
			)
		)
		(duplicate_pad_numbers_are_jumpers no)
		(pad "1" thru_hole circle
			(at 0 0 180)
			(size 0.4572 0.4572)
			(drill 0.20574)
			(layers "*.Cu" "*.Mask")
			(remove_unused_layers no)
			(net "DDR0_32A_DQ28")
			(clearance 0.1143)
			(thermal_gap 0.1143)
		)
	)
	(footprint ""
		(layer "B.Cu")
		(at 48.781691 6.542024 90)
		(property "Reference" "C281"
			(at 0 0 90)
			(layer "B.SilkS")
			(hide yes)
			(effects
				(font
					(size 1.27 1.27)
				)
				(justify mirror)
			)
		)
		(property "Value" "22UF"
			(at 0.148158 1.7526 0)
			(unlocked yes)
			(layer "B.Fab")
			(hide yes)
			(effects
				(font
					(size 1.27 0.9652)
					(thickness 0.000001)
				)
				(justify left mirror)
			)
		)
		(property "Device Type" "CAPC0063"
			(at 0.148158 1.7526 0)
			(unlocked yes)
			(layer "B.Fab")
			(hide yes)
			(effects
				(font
					(size 1.27 0.9652)
					(thickness 0.000001)
				)
				(justify left mirror)
			)
		)
		(duplicate_pad_numbers_are_jumpers no)
		(fp_circle
			(center 0 0)
			(end 0 0.127)
			(stroke
				(width 0.2032)
				(type default)
			)
			(fill no)
			(layer "B.SilkS")
		)
		(fp_poly
			(pts
				(xy -0.7874 -1.6637) (xy 0.7874 -1.6637) (xy 0.7874 1.6637) (xy -0.7874 1.6637)
			)
			(stroke
				(width 0)
				(type default)
			)
			(fill no)
			(layer "B.CrtYd")
		)
		(fp_line
			(start 0.4064 -0.7874)
			(end -0.4064 -0.7874)
			(stroke
				(width 0.0254)
				(type default)
			)
			(layer "B.Fab")
		)
		(fp_line
			(start -0.4064 -0.7874)
			(end -0.4064 0.8128)
			(stroke
				(width 0.0254)
				(type default)
			)
			(layer "B.Fab")
		)
		(fp_line
			(start 0.4064 0.8128)
			(end 0.4064 -0.7874)
			(stroke
				(width 0.0254)
				(type default)
			)
			(layer "B.Fab")
		)
		(fp_line
			(start -0.4064 0.8128)
			(end 0.4064 0.8128)
			(stroke
				(width 0.0254)
				(type default)
			)
			(layer "B.Fab")
		)
		(pad "1" smd rect
			(at 0 -0.8001 270)
			(size 0.8636 0.9652)
			(layers "B.Cu" "B.Mask" "B.Paste")
			(net "VDDA_SERDES")
		)
		(pad "2" smd rect
			(at 0 0.8001 270)
			(size 0.8636 0.9652)
			(layers "B.Cu" "B.Mask" "B.Paste")
			(net "GND")
		)
		(zone
			(layer "B.Cu")
			(hatch none 0.5)
			(connect_pads
				(clearance 0)
			)
			(min_thickness 0.25)
			(keepout
				(tracks not_allowed)
				(vias allowed)
				(pads allowed)
				(copperpour not_allowed)
				(footprints allowed)
			)
			(placement
				(enabled no)
				(sheetname "")
			)
			(fill
				(thermal_gap 0.5)
				(thermal_bridge_width 0.5)
				(island_removal_mode 0)
			)
			(polygon
				(pts
					(xy 48.527691 6.478524) (xy 48.527691 6.605524) (xy 49.035691 6.605524) (xy 49.035691 6.478524)
				)
			)
		)
	)
	(footprint ""
		(layer "B.Cu")
		(at 72.251011 6.698996)
		(property "Reference" "V_A-DQ11"
			(at 0 0 0)
			(layer "B.SilkS")
			(hide yes)
			(effects
				(font
					(size 1.27 1.27)
				)
				(justify mirror)
			)
		)
		(property "Value" ""
			(at 0 0 0)
			(layer "B.Fab")
			(effects
				(font
					(size 1.27 1.27)
				)
				(justify mirror)
			)
		)
		(duplicate_pad_numbers_are_jumpers no)
		(pad "1" thru_hole circle
			(at 0 0 180)
			(size 0.4572 0.4572)
			(drill 0.20574)
			(layers "*.Cu" "*.Mask")
			(remove_unused_layers no)
			(net "DDR0_32A_DQ11")
			(clearance 0.1143)
			(thermal_gap 0.1143)
		)
	)
)
